# T6G (Grand Teton) — schematic netlist excerpt (pin names and nets, part order shuffled) for the footprints in the layout excerpt that follows; sources: Cadence DE-HDL packaged netlist, KiCad conversion of 04192023_DAF0TMB3IC0_F0TG_MB_C_brd_V02_OCP.brd

R8250  Q_RES  33 5% CHIP  pkg 0402LF  page 217 : A = PVDDCR_CPU1_P1_SMB_ALERT ; B = PVDDCR_CPU1_P1_SMB_ALERT_R
C1227  Q_CAP  100NF 50V 10% X7R  pkg C0402  page 188 : A = P5V ; B = GND

(kicad_pcb
	(version 20260206)
	(generator "pcbnew")
	(generator_version "10.0")
	(general
		(thickness 1.6)
		(legacy_teardrops no)
	)
	(paper "A4")
	(title_block
		(title "04192023_DAF0TMB3IC0_F0TG_MB_C_brd_V02_OCP.brd")
		(comment 1 "Grand Teton / footprints 4159-4160 of 8354")
	)
	(layers
		(0 "F.Cu" signal "TOP")
		(4 "In1.Cu" signal "GND")
		(6 "In2.Cu" signal "IN1")
		(8 "In3.Cu" signal "GND1")
		(10 "In4.Cu" signal "IN2")
		(12 "In5.Cu" signal "GND2")
		(14 "In6.Cu" signal "IN3")
		(16 "In7.Cu" signal "GND3")
		(18 "In8.Cu" signal "VCC")
		(20 "In9.Cu" signal "VCC1")
		(22 "In10.Cu" signal "GND4")
		(24 "In11.Cu" signal "IN4")
		(26 "In12.Cu" signal "GND5")
		(28 "In13.Cu" signal "IN5")
		(30 "In14.Cu" signal "GND6")
		(32 "In15.Cu" signal "IN6")
		(34 "In16.Cu" signal "GND7")
		(2 "B.Cu" signal "BOTTOM")
		(9 "F.Adhes" user "F.Adhesive")
		(11 "B.Adhes" user "B.Adhesive")
		(13 "F.Paste" user "Package Geometry/Pastemask Top")
		(15 "B.Paste" user "Package Geometry/Pastemask Bottom")
		(5 "F.SilkS" user "Ref Des/Silkscreen Top")
		(7 "B.SilkS" user "Ref Des/Silkscreen Bottom")
		(1 "F.Mask" user "Board Geometry/Soldermask Top")
		(3 "B.Mask" user "Board Geometry/Soldermask Bottom")
		(17 "Dwgs.User" user "User.Drawings")
		(19 "Cmts.User" user "User.Comments")
		(21 "Eco1.User" user "User.Eco1")
		(23 "Eco2.User" user "User.Eco2")
		(25 "Edge.Cuts" user "Board Geometry/Outline")
		(27 "Margin" user)
		(31 "F.CrtYd" user "Package Geometry/Place Bound Top")
		(29 "B.CrtYd" user "Package Geometry/Place Bound Bottom")
		(35 "F.Fab" user "Ref Des/Assembly Top")
		(33 "B.Fab" user "Ref Des/Assembly Bottom")
	)
	(footprint ""
		(layer "F.Cu")
		(at 22.479 -365.76)
		(property "Reference" "R8250"
			(at 0 0 0)
			(layer "F.SilkS")
			(hide yes)
			(effects
				(font
					(size 1.27 1.27)
				)
			)
		)
		(property "Value" ""
			(at 0 0 0)
			(layer "F.Fab")
			(effects
				(font
					(size 1.27 1.27)
				)
			)
		)
		(duplicate_pad_numbers_are_jumpers no)
		(fp_line
			(start -0.7874 -0.4064)
			(end 0.7874 -0.4064)
			(stroke
				(width 0.1524)
				(type default)
			)
			(layer "F.SilkS")
		)
		(fp_line
			(start -0.7874 0.4064)
			(end -0.7874 -0.4064)
			(stroke
				(width 0.1524)
				(type default)
			)
			(layer "F.SilkS")
		)
		(fp_line
			(start 0.7874 -0.4064)
			(end 0.7874 0.4064)
			(stroke
				(width 0.1524)
				(type default)
			)
			(layer "F.SilkS")
		)
		(fp_line
			(start 0.7874 0.4064)
			(end -0.7874 0.4064)
			(stroke
				(width 0.1524)
				(type default)
			)
			(layer "F.SilkS")
		)
		(fp_line
			(start -0.67945 -0.305054)
			(end -0.12065 -0.305054)
			(stroke
				(width 0.1)
				(type default)
			)
			(layer "F.Fab")
		)
		(fp_line
			(start -0.67945 0.3048)
			(end -0.67945 -0.305054)
			(stroke
				(width 0.1)
				(type default)
			)
			(layer "F.Fab")
		)
		(fp_line
			(start -0.12065 -0.305054)
			(end -0.12065 -0.2794)
			(stroke
				(width 0.1)
				(type default)
			)
			(layer "F.Fab")
		)
		(fp_line
			(start -0.12065 -0.2794)
			(end 0.12065 -0.2794)
			(stroke
				(width 0.1)
				(type default)
			)
			(layer "F.Fab")
		)
		(fp_line
			(start -0.12065 0.2794)
			(end -0.12065 0.3048)
			(stroke
				(width 0.1)
				(type default)
			)
			(layer "F.Fab")
		)
		(fp_line
			(start -0.12065 0.3048)
			(end -0.67945 0.3048)
			(stroke
				(width 0.1)
				(type default)
			)
			(layer "F.Fab")
		)
		(fp_line
			(start 0.120396 0.2794)
			(end -0.12065 0.2794)
			(stroke
				(width 0.1)
				(type default)
			)
			(layer "F.Fab")
		)
		(fp_line
			(start 0.120396 0.3048)
			(end 0.120396 0.2794)
			(stroke
				(width 0.1)
				(type default)
			)
			(layer "F.Fab")
		)
		(fp_line
			(start 0.12065 -0.3048)
			(end 0.67945 -0.3048)
			(stroke
				(width 0.1)
				(type default)
			)
			(layer "F.Fab")
		)
		(fp_line
			(start 0.12065 -0.2794)
			(end 0.12065 -0.3048)
			(stroke
				(width 0.1)
				(type default)
			)
			(layer "F.Fab")
		)
		(fp_line
			(start 0.67945 -0.3048)
			(end 0.67945 0.3048)
			(stroke
				(width 0.1)
				(type default)
			)
			(layer "F.Fab")
		)
		(fp_line
			(start 0.67945 0.3048)
			(end 0.120396 0.3048)
			(stroke
				(width 0.1)
				(type default)
			)
			(layer "F.Fab")
		)
		(pad "1" smd circle
			(at -0.40005 0)
			(size 0 0)
			(layers "F.Cu" "F.Mask" "F.Paste")
			(net "PVDDCR_CPU1_P1_SMB_ALERT")
		)
		(pad "2" smd circle
			(at 0.40005 0)
			(size 0 0)
			(layers "F.Cu" "F.Mask" "F.Paste")
			(net "PVDDCR_CPU1_P1_SMB_ALERT_R")
		)
	)
	(footprint ""
		(layer "F.Cu")
		(at 396.58163 -146.354292 -90)
		(property "Reference" "C1227"
			(at 0 0 270)
			(layer "F.SilkS")
			(hide yes)
			(effects
				(font
					(size 1.27 1.27)
				)
			)
		)
		(property "Value" ""
			(at 0 0 270)
			(layer "F.Fab")
			(effects
				(font
					(size 1.27 1.27)
				)
			)
		)
		(duplicate_pad_numbers_are_jumpers no)
		(fp_line
			(start -0.7874 0.4064)
			(end -0.7874 -0.4064)
			(stroke
				(width 0.1524)
				(type default)
			)
			(layer "F.SilkS")
		)
		(fp_line
			(start 0.7874 0.4064)
			(end -0.7874 0.4064)
			(stroke
				(width 0.1524)
				(type default)
			)
			(layer "F.SilkS")
		)
		(fp_line
			(start -0.7874 -0.4064)
			(end 0.7874 -0.4064)
			(stroke
				(width 0.1524)
				(type default)
			)
			(layer "F.SilkS")
		)
		(fp_line
			(start 0.7874 -0.4064)
			(end 0.7874 0.4064)
			(stroke
				(width 0.1524)
				(type default)
			)
			(layer "F.SilkS")
		)
		(fp_line
			(start -0.67945 0.3048)
			(end -0.67945 -0.305054)
			(stroke
				(width 0.1)
				(type default)
			)
			(layer "F.Fab")
		)
		(fp_line
			(start -0.12065 0.3048)
			(end -0.67945 0.3048)
			(stroke
				(width 0.1)
				(type default)
			)
			(layer "F.Fab")
		)
		(fp_line
			(start 0.120396 0.3048)
			(end 0.120396 0.2794)
			(stroke
				(width 0.1)
				(type default)
			)
			(layer "F.Fab")
		)
		(fp_line
			(start 0.67945 0.3048)
			(end 0.120396 0.3048)
			(stroke
				(width 0.1)
				(type default)
			)
			(layer "F.Fab")
		)
		(fp_line
			(start -0.12065 0.2794)
			(end -0.12065 0.3048)
			(stroke
				(width 0.1)
				(type default)
			)
			(layer "F.Fab")
		)
		(fp_line
			(start 0.120396 0.2794)
			(end -0.12065 0.2794)
			(stroke
				(width 0.1)
				(type default)
			)
			(layer "F.Fab")
		)
		(fp_line
			(start -0.12065 -0.2794)
			(end 0.12065 -0.2794)
			(stroke
				(width 0.1)
				(type default)
			)
			(layer "F.Fab")
		)
		(fp_line
			(start 0.12065 -0.2794)
			(end 0.12065 -0.3048)
			(stroke
				(width 0.1)
				(type default)
			)
			(layer "F.Fab")
		)
		(fp_line
			(start 0.12065 -0.3048)
			(end 0.67945 -0.3048)
			(stroke
				(width 0.1)
				(type default)
			)
			(layer "F.Fab")
		)
		(fp_line
			(start 0.67945 -0.3048)
			(end 0.67945 0.3048)
			(stroke
				(width 0.1)
				(type default)
			)
			(layer "F.Fab")
		)
		(fp_line
			(start -0.67945 -0.305054)
			(end -0.12065 -0.305054)
			(stroke
				(width 0.1)
				(type default)
			)
			(layer "F.Fab")
		)
		(fp_line
			(start -0.12065 -0.305054)
			(end -0.12065 -0.2794)
			(stroke
				(width 0.1)
				(type default)
			)
			(layer "F.Fab")
		)
		(pad "1" smd circle
			(at -0.40005 0 270)
			(size 0 0)
			(layers "F.Cu" "F.Mask" "F.Paste")
			(net "P5V")
		)
		(pad "2" smd circle
			(at 0.40005 0 270)
			(size 0 0)
			(layers "F.Cu" "F.Mask" "F.Paste")
			(net "GND")
		)
	)
)
